(kicad_pcb
	(version 20260206)
	(generator "pcbnew")
	(generator_version "10.0")
	(general
		(thickness 1.6)
		(legacy_teardrops no)
	)
	(paper "A4")
	(title_block
		(title "04192023_DAF0TMB3IC0_F0TG_MB_C_brd_V02_OCP.brd")
		(comment 1 "Grand Teton / footprints 1946-1952 of 8354")
	)
	(layers
		(0 "F.Cu" signal "TOP")
		(4 "In1.Cu" signal "GND")
		(6 "In2.Cu" signal "IN1")
		(8 "In3.Cu" signal "GND1")
		(10 "In4.Cu" signal "IN2")
		(12 "In5.Cu" signal "GND2")
		(14 "In6.Cu" signal "IN3")
		(16 "In7.Cu" signal "GND3")
		(18 "In8.Cu" signal "VCC")
		(20 "In9.Cu" signal "VCC1")
		(22 "In10.Cu" signal "GND4")
		(24 "In11.Cu" signal "IN4")
		(26 "In12.Cu" signal "GND5")
		(28 "In13.Cu" signal "IN5")
		(30 "In14.Cu" signal "GND6")
		(32 "In15.Cu" signal "IN6")
		(34 "In16.Cu" signal "GND7")
		(2 "B.Cu" signal "BOTTOM")
		(9 "F.Adhes" user "F.Adhesive")
		(11 "B.Adhes" user "B.Adhesive")
		(13 "F.Paste" user "Package Geometry/Pastemask Top")
		(15 "B.Paste" user "Package Geometry/Pastemask Bottom")
		(5 "F.SilkS" user "Ref Des/Silkscreen Top")
		(7 "B.SilkS" user "Ref Des/Silkscreen Bottom")
		(1 "F.Mask" user "Board Geometry/Soldermask Top")
		(3 "B.Mask" user "Board Geometry/Soldermask Bottom")
		(17 "Dwgs.User" user "User.Drawings")
		(19 "Cmts.User" user "User.Comments")
		(21 "Eco1.User" user "User.Eco1")
		(23 "Eco2.User" user "User.Eco2")
		(25 "Edge.Cuts" user "Board Geometry/Outline")
		(27 "Margin" user)
		(31 "F.CrtYd" user "Package Geometry/Place Bound Top")
		(29 "B.CrtYd" user "Package Geometry/Place Bound Bottom")
		(35 "F.Fab" user "Ref Des/Assembly Top")
		(33 "B.Fab" user "Ref Des/Assembly Bottom")
	)
	(footprint ""
		(layer "F.Cu")
		(at 463.735928 -94.317566)
		(property "Reference" "R3233"
			(at 0 0 0)
			(layer "F.SilkS")
			(hide yes)
			(effects
				(font
					(size 1.27 1.27)
				)
			)
		)
		(property "Value" ""
			(at 0 0 0)
			(layer "F.Fab")
			(effects
				(font
					(size 1.27 1.27)
				)
			)
		)
		(duplicate_pad_numbers_are_jumpers no)
		(fp_line
			(start -0.7874 -0.4064)
			(end 0.7874 -0.4064)
			(stroke
				(width 0.1524)
				(type default)
			)
			(layer "F.SilkS")
		)
		(fp_line
			(start -0.7874 0.4064)
			(end -0.7874 -0.4064)
			(stroke
				(width 0.1524)
				(type default)
			)
			(layer "F.SilkS")
		)
		(fp_line
			(start 0.7874 -0.4064)
			(end 0.7874 0.4064)
			(stroke
				(width 0.1524)
				(type default)
			)
			(layer "F.SilkS")
		)
		(fp_line
			(start 0.7874 0.4064)
			(end -0.7874 0.4064)
			(stroke
				(width 0.1524)
				(type default)
			)
			(layer "F.SilkS")
		)
		(fp_line
			(start -0.67945 -0.305054)
			(end -0.12065 -0.305054)
			(stroke
				(width 0.1)
				(type default)
			)
			(layer "F.Fab")
		)
		(fp_line
			(start -0.67945 0.3048)
			(end -0.67945 -0.305054)
			(stroke
				(width 0.1)
				(type default)
			)
			(layer "F.Fab")
		)
		(fp_line
			(start -0.12065 -0.305054)
			(end -0.12065 -0.2794)
			(stroke
				(width 0.1)
				(type default)
			)
			(layer "F.Fab")
		)
		(fp_line
			(start -0.12065 -0.2794)
			(end 0.12065 -0.2794)
			(stroke
				(width 0.1)
				(type default)
			)
			(layer "F.Fab")
		)
		(fp_line
			(start -0.12065 0.2794)
			(end -0.12065 0.3048)
			(stroke
				(width 0.1)
				(type default)
			)
			(layer "F.Fab")
		)
		(fp_line
			(start -0.12065 0.3048)
			(end -0.67945 0.3048)
			(stroke
				(width 0.1)
				(type default)
			)
			(layer "F.Fab")
		)
		(fp_line
			(start 0.120396 0.2794)
			(end -0.12065 0.2794)
			(stroke
				(width 0.1)
				(type default)
			)
			(layer "F.Fab")
		)
		(fp_line
			(start 0.120396 0.3048)
			(end 0.120396 0.2794)
			(stroke
				(width 0.1)
				(type default)
			)
			(layer "F.Fab")
		)
		(fp_line
			(start 0.12065 -0.3048)
			(end 0.67945 -0.3048)
			(stroke
				(width 0.1)
				(type default)
			)
			(layer "F.Fab")
		)
		(fp_line
			(start 0.12065 -0.2794)
			(end 0.12065 -0.3048)
			(stroke
				(width 0.1)
				(type default)
			)
			(layer "F.Fab")
		)
		(fp_line
			(start 0.67945 -0.3048)
			(end 0.67945 0.3048)
			(stroke
				(width 0.1)
				(type default)
			)
			(layer "F.Fab")
		)
		(fp_line
			(start 0.67945 0.3048)
			(end 0.120396 0.3048)
			(stroke
				(width 0.1)
				(type default)
			)
			(layer "F.Fab")
		)
		(pad "1" smd circle
			(at -0.40005 0)
			(size 0 0)
			(layers "F.Cu" "F.Mask" "F.Paste")
			(net "RST_HP_OCP_SFF_R_N")
		)
		(pad "2" smd circle
			(at 0.40005 0)
			(size 0 0)
			(layers "F.Cu" "F.Mask" "F.Paste")
			(net "RST_SMB_OCP_SFF_N")
		)
	)
	(footprint ""
		(layer "F.Cu")
		(at 294.421052 -118.285514)
		(property "Reference" "R3581"
			(at 0 0 0)
			(layer "F.SilkS")
			(hide yes)
			(effects
				(font
					(size 1.27 1.27)
				)
			)
		)
		(property "Value" ""
			(at 0 0 0)
			(layer "F.Fab")
			(effects
				(font
					(size 1.27 1.27)
				)
			)
		)
		(duplicate_pad_numbers_are_jumpers no)
		(fp_line
			(start -0.7874 -0.4064)
			(end 0.7874 -0.4064)
			(stroke
				(width 0.1524)
				(type default)
			)
			(layer "F.SilkS")
		)
		(fp_line
			(start -0.7874 0.4064)
			(end -0.7874 -0.4064)
			(stroke
				(width 0.1524)
				(type default)
			)
			(layer "F.SilkS")
		)
		(fp_line
			(start 0.7874 -0.4064)
			(end 0.7874 0.4064)
			(stroke
				(width 0.1524)
				(type default)
			)
			(layer "F.SilkS")
		)
		(fp_line
			(start 0.7874 0.4064)
			(end -0.7874 0.4064)
			(stroke
				(width 0.1524)
				(type default)
			)
			(layer "F.SilkS")
		)
		(fp_line
			(start -0.67945 -0.305054)
			(end -0.12065 -0.305054)
			(stroke
				(width 0.1)
				(type default)
			)
			(layer "F.Fab")
		)
		(fp_line
			(start -0.67945 0.3048)
			(end -0.67945 -0.305054)
			(stroke
				(width 0.1)
				(type default)
			)
			(layer "F.Fab")
		)
		(fp_line
			(start -0.12065 -0.305054)
			(end -0.12065 -0.2794)
			(stroke
				(width 0.1)
				(type default)
			)
			(layer "F.Fab")
		)
		(fp_line
			(start -0.12065 -0.2794)
			(end 0.12065 -0.2794)
			(stroke
				(width 0.1)
				(type default)
			)
			(layer "F.Fab")
		)
		(fp_line
			(start -0.12065 0.2794)
			(end -0.12065 0.3048)
			(stroke
				(width 0.1)
				(type default)
			)
			(layer "F.Fab")
		)
		(fp_line
			(start -0.12065 0.3048)
			(end -0.67945 0.3048)
			(stroke
				(width 0.1)
				(type default)
			)
			(layer "F.Fab")
		)
		(fp_line
			(start 0.120396 0.2794)
			(end -0.12065 0.2794)
			(stroke
				(width 0.1)
				(type default)
			)
			(layer "F.Fab")
		)
		(fp_line
			(start 0.120396 0.3048)
			(end 0.120396 0.2794)
			(stroke
				(width 0.1)
				(type default)
			)
			(layer "F.Fab")
		)
		(fp_line
			(start 0.12065 -0.3048)
			(end 0.67945 -0.3048)
			(stroke
				(width 0.1)
				(type default)
			)
			(layer "F.Fab")
		)
		(fp_line
			(start 0.12065 -0.2794)
			(end 0.12065 -0.3048)
			(stroke
				(width 0.1)
				(type default)
			)
			(layer "F.Fab")
		)
		(fp_line
			(start 0.67945 -0.3048)
			(end 0.67945 0.3048)
			(stroke
				(width 0.1)
				(type default)
			)
			(layer "F.Fab")
		)
		(fp_line
			(start 0.67945 0.3048)
			(end 0.120396 0.3048)
			(stroke
				(width 0.1)
				(type default)
			)
			(layer "F.Fab")
		)
		(pad "1" smd circle
			(at -0.40005 0)
			(size 0 0)
			(layers "F.Cu" "F.Mask" "F.Paste")
			(net "SMB_INA230_3V3AUX_SDA_R")
		)
		(pad "2" smd circle
			(at 0.40005 0)
			(size 0 0)
			(layers "F.Cu" "F.Mask" "F.Paste")
			(net "SMB_INA230_3V3AUX_SDA")
		)
	)
	(footprint ""
		(layer "F.Cu")
		(at 180.710332 -92.67444 -90)
		(property "Reference" "R6149"
			(at 0 0 270)
			(layer "F.SilkS")
			(hide yes)
			(effects
				(font
					(size 1.27 1.27)
				)
			)
		)
		(property "Value" ""
			(at 0 0 270)
			(layer "F.Fab")
			(effects
				(font
					(size 1.27 1.27)
				)
			)
		)
		(duplicate_pad_numbers_are_jumpers no)
		(fp_line
			(start -0.7874 0.4064)
			(end -0.7874 -0.4064)
			(stroke
				(width 0.1524)
				(type default)
			)
			(layer "F.SilkS")
		)
		(fp_line
			(start 0.7874 0.4064)
			(end -0.7874 0.4064)
			(stroke
				(width 0.1524)
				(type default)
			)
			(layer "F.SilkS")
		)
		(fp_line
			(start -0.7874 -0.4064)
			(end 0.7874 -0.4064)
			(stroke
				(width 0.1524)
				(type default)
			)
			(layer "F.SilkS")
		)
		(fp_line
			(start 0.7874 -0.4064)
			(end 0.7874 0.4064)
			(stroke
				(width 0.1524)
				(type default)
			)
			(layer "F.SilkS")
		)
		(fp_line
			(start -0.67945 0.3048)
			(end -0.67945 -0.305054)
			(stroke
				(width 0.1)
				(type default)
			)
			(layer "F.Fab")
		)
		(fp_line
			(start -0.12065 0.3048)
			(end -0.67945 0.3048)
			(stroke
				(width 0.1)
				(type default)
			)
			(layer "F.Fab")
		)
		(fp_line
			(start 0.120396 0.3048)
			(end 0.120396 0.2794)
			(stroke
				(width 0.1)
				(type default)
			)
			(layer "F.Fab")
		)
		(fp_line
			(start 0.67945 0.3048)
			(end 0.120396 0.3048)
			(stroke
				(width 0.1)
				(type default)
			)
			(layer "F.Fab")
		)
		(fp_line
			(start -0.12065 0.2794)
			(end -0.12065 0.3048)
			(stroke
				(width 0.1)
				(type default)
			)
			(layer "F.Fab")
		)
		(fp_line
			(start 0.120396 0.2794)
			(end -0.12065 0.2794)
			(stroke
				(width 0.1)
				(type default)
			)
			(layer "F.Fab")
		)
		(fp_line
			(start -0.12065 -0.2794)
			(end 0.12065 -0.2794)
			(stroke
				(width 0.1)
				(type default)
			)
			(layer "F.Fab")
		)
		(fp_line
			(start 0.12065 -0.2794)
			(end 0.12065 -0.3048)
			(stroke
				(width 0.1)
				(type default)
			)
			(layer "F.Fab")
		)
		(fp_line
			(start 0.12065 -0.3048)
			(end 0.67945 -0.3048)
			(stroke
				(width 0.1)
				(type default)
			)
			(layer "F.Fab")
		)
		(fp_line
			(start 0.67945 -0.3048)
			(end 0.67945 0.3048)
			(stroke
				(width 0.1)
				(type default)
			)
			(layer "F.Fab")
		)
		(fp_line
			(start -0.67945 -0.305054)
			(end -0.12065 -0.305054)
			(stroke
				(width 0.1)
				(type default)
			)
			(layer "F.Fab")
		)
		(fp_line
			(start -0.12065 -0.305054)
			(end -0.12065 -0.2794)
			(stroke
				(width 0.1)
				(type default)
			)
			(layer "F.Fab")
		)
		(pad "1" smd circle
			(at -0.40005 0 270)
			(size 0 0)
			(layers "F.Cu" "F.Mask" "F.Paste")
			(net "FAB_BMC_REV_ID2")
		)
		(pad "2" smd circle
			(at 0.40005 0 270)
			(size 0 0)
			(layers "F.Cu" "F.Mask" "F.Paste")
			(net "GND")
		)
	)
	(footprint ""
		(layer "F.Cu")
		(at 398.046956 -186.488324 180)
		(property "Reference" "PL63"
			(at -4.603242 2.798064 90)
			(unlocked yes)
			(layer "F.SilkS")
			(effects
				(font
					(size 0.7874 0.5842)
					(thickness 0.1524)
				)
				(justify left)
			)
		)
		(property "Value" ""
			(at 0 0 180)
			(layer "F.Fab")
			(effects
				(font
					(size 1.27 1.27)
				)
			)
		)
		(duplicate_pad_numbers_are_jumpers no)
		(fp_line
			(start 3.750056 5.500116)
			(end 3.750056 -5.500116)
			(stroke
				(width 0.1524)
				(type default)
			)
			(layer "F.SilkS")
		)
		(fp_line
			(start 3.750056 -5.500116)
			(end 2.393442 -5.500116)
			(stroke
				(width 0.1524)
				(type default)
			)
			(layer "F.SilkS")
		)
		(fp_line
			(start 2.393442 5.500116)
			(end 3.750056 5.500116)
			(stroke
				(width 0.1524)
				(type default)
			)
			(layer "F.SilkS")
		)
		(fp_line
			(start -2.393442 5.500116)
			(end -3.750056 5.500116)
			(stroke
				(width 0.1524)
				(type default)
			)
			(layer "F.SilkS")
		)
		(fp_line
			(start -3.750056 5.500116)
			(end -3.750056 -5.500116)
			(stroke
				(width 0.1524)
				(type default)
			)
			(layer "F.SilkS")
		)
		(fp_line
			(start -3.750056 -5.500116)
			(end -2.393442 -5.500116)
			(stroke
				(width 0.1524)
				(type default)
			)
			(layer "F.SilkS")
		)
		(fp_poly
			(pts
				(xy -3.9116 -4.249928) (xy -4.543044 -3.934206) (xy -4.543044 -4.56565)
			)
			(stroke
				(width 0)
				(type default)
			)
			(fill yes)
			(layer "F.SilkS")
		)
		(fp_line
			(start 3.750056 5.500116)
			(end 3.750056 -5.500116)
			(stroke
				(width 0.1)
				(type default)
			)
			(layer "F.Fab")
		)
		(fp_line
			(start 3.750056 -5.500116)
			(end -3.750056 -5.500116)
			(stroke
				(width 0.1)
				(type default)
			)
			(layer "F.Fab")
		)
		(fp_line
			(start -3.750056 5.500116)
			(end 3.750056 5.500116)
			(stroke
				(width 0.1)
				(type default)
			)
			(layer "F.Fab")
		)
		(fp_line
			(start -3.750056 -5.500116)
			(end -3.750056 5.500116)
			(stroke
				(width 0.1)
				(type default)
			)
			(layer "F.Fab")
		)
		(fp_poly
			(pts
				(xy -4.9276 -4.757928) (xy -4.9276 -3.741928) (xy -3.9116 -4.249928)
			)
			(stroke
				(width 0)
				(type default)
			)
			(fill yes)
			(layer "F.Fab")
		)
		(pad "1" smd rect
			(at 0 -4.249928 90)
			(size 2.413 4.5212)
			(layers "F.Cu" "F.Mask" "F.Paste")
			(net "SW_PVDDCR_SOC_P0_SW1")
		)
		(pad "2" smd rect
			(at 0 -1.175004 90)
			(size 1.3716 4.5212)
			(layers "F.Cu" "F.Mask" "F.Paste")
			(net "IND_SOC_P0_CPL2")
		)
		(pad "3" smd rect
			(at 0 1.175004 90)
			(size 1.3716 4.5212)
			(layers "F.Cu" "F.Mask" "F.Paste")
			(net "GND")
		)
		(pad "4" smd rect
			(at 0 4.249928 90)
			(size 2.413 4.5212)
			(layers "F.Cu" "F.Mask" "F.Paste")
			(net "PVDDCR_SOC_P0")
		)
	)
	(footprint ""
		(layer "F.Cu")
		(at 91.568524 -408.517344 -90)
		(property "Reference" "C6657"
			(at 0 0 270)
			(layer "F.SilkS")
			(hide yes)
			(effects
				(font
					(size 1.27 1.27)
				)
			)
		)
		(property "Value" ""
			(at 0 0 270)
			(layer "F.Fab")
			(effects
				(font
					(size 1.27 1.27)
				)
			)
		)
		(duplicate_pad_numbers_are_jumpers no)
		(fp_line
			(start -0.299974 0.150114)
			(end -0.299974 -0.150114)
			(stroke
				(width 0.1)
				(type default)
			)
			(layer "F.Fab")
		)
		(fp_line
			(start 0.299974 0.150114)
			(end -0.299974 0.150114)
			(stroke
				(width 0.1)
				(type default)
			)
			(layer "F.Fab")
		)
		(fp_line
			(start -0.299974 -0.150114)
			(end 0.299974 -0.150114)
			(stroke
				(width 0.1)
				(type default)
			)
			(layer "F.Fab")
		)
		(fp_line
			(start 0.299974 -0.150114)
			(end 0.299974 0.150114)
			(stroke
				(width 0.1)
				(type default)
			)
			(layer "F.Fab")
		)
		(pad "1" smd rect
			(at -0.2667 0 270)
			(size 0.3048 0.381)
			(layers "F.Cu" "F.Mask" "F.Paste")
			(net "P5E_CPU1_P0_TX_BUF_C_DP<14>")
		)
		(pad "2" smd rect
			(at 0.2667 0 270)
			(size 0.3048 0.381)
			(layers "F.Cu" "F.Mask" "F.Paste")
			(net "P5E_CPU1_P0_TX_BUF_DP<14>")
		)
	)
	(footprint ""
		(layer "F.Cu")
		(at 241.114834 -374.81129 90)
		(property "Reference" "PD17"
			(at 2.0574 -3.343148 90)
			(unlocked yes)
			(layer "F.SilkS")
			(effects
				(font
					(size 0.7874 0.5842)
					(thickness 0.1524)
				)
			)
		)
		(property "Value" ""
			(at 0 0 90)
			(layer "F.Fab")
			(effects
				(font
					(size 1.27 1.27)
				)
			)
		)
		(duplicate_pad_numbers_are_jumpers no)
		(fp_line
			(start 3.541776 -2.54)
			(end 3.541776 2.54)
			(stroke
				(width 0.1524)
				(type default)
			)
			(layer "F.SilkS")
		)
		(fp_line
			(start -3.539744 -2.54)
			(end 3.541776 -2.54)
			(stroke
				(width 0.1524)
				(type default)
			)
			(layer "F.SilkS")
		)
		(fp_line
			(start 3.541776 2.54)
			(end -3.539744 2.54)
			(stroke
				(width 0.1524)
				(type default)
			)
			(layer "F.SilkS")
		)
		(fp_line
			(start -3.539744 2.54)
			(end -3.539744 -2.54)
			(stroke
				(width 0.1524)
				(type default)
			)
			(layer "F.SilkS")
		)
		(fp_poly
			(pts
				(xy -2.86258 2.690876) (xy -2.35458 3.706876) (xy -3.37058 3.706876)
			)
			(stroke
				(width 0)
				(type default)
			)
			(fill yes)
			(layer "F.SilkS")
		)
		(fp_line
			(start 3.074924 -2.175002)
			(end 3.074924 2.175002)
			(stroke
				(width 0.1)
				(type default)
			)
			(layer "F.Fab")
		)
		(fp_line
			(start -3.074924 -2.175002)
			(end 3.074924 -2.175002)
			(stroke
				(width 0.1)
				(type default)
			)
			(layer "F.Fab")
		)
		(fp_line
			(start 3.074924 2.175002)
			(end -3.074924 2.175002)
			(stroke
				(width 0.1)
				(type default)
			)
			(layer "F.Fab")
		)
		(fp_line
			(start -3.074924 2.175002)
			(end -3.074924 -2.175002)
			(stroke
				(width 0.1)
				(type default)
			)
			(layer "F.Fab")
		)
		(fp_poly
			(pts
				(xy -4.699 0.531876) (xy -4.699 1.547876) (xy -3.683 1.039876)
			)
			(stroke
				(width 0)
				(type default)
			)
			(fill yes)
			(layer "F.Fab")
		)
		(pad "1" smd rect
			(at -2.765044 1.039876 270)
			(size 1.27 1.4224)
			(layers "F.Cu" "F.Mask" "F.Paste")
			(net "GND")
		)
		(pad "2" smd rect
			(at -2.765044 -1.039876 270)
			(size 1.27 1.4224)
			(layers "F.Cu" "F.Mask" "F.Paste")
			(net "GND")
		)
		(pad "K" smd rect
			(at 1.039876 0 270)
			(size 4.7244 4.8006)
			(layers "F.Cu" "F.Mask" "F.Paste")
			(net "P12V_AUX")
		)
	)
	(footprint ""
		(layer "F.Cu")
		(at 303.200308 -41.906698)
		(property "Reference" "R3669"
			(at 0 0 0)
			(layer "F.SilkS")
			(hide yes)
			(effects
				(font
					(size 1.27 1.27)
				)
			)
		)
		(property "Value" ""
			(at 0 0 0)
			(layer "F.Fab")
			(effects
				(font
					(size 1.27 1.27)
				)
			)
		)
		(duplicate_pad_numbers_are_jumpers no)
		(fp_line
			(start -0.7874 -0.4064)
			(end 0.7874 -0.4064)
			(stroke
				(width 0.1524)
				(type default)
			)
			(layer "F.SilkS")
		)
		(fp_line
			(start -0.7874 0.4064)
			(end -0.7874 -0.4064)
			(stroke
				(width 0.1524)
				(type default)
			)
			(layer "F.SilkS")
		)
		(fp_line
			(start 0.7874 -0.4064)
			(end 0.7874 0.4064)
			(stroke
				(width 0.1524)
				(type default)
			)
			(layer "F.SilkS")
		)
		(fp_line
			(start 0.7874 0.4064)
			(end -0.7874 0.4064)
			(stroke
				(width 0.1524)
				(type default)
			)
			(layer "F.SilkS")
		)
		(fp_line
			(start -0.67945 -0.305054)
			(end -0.12065 -0.305054)
			(stroke
				(width 0.1)
				(type default)
			)
			(layer "F.Fab")
		)
		(fp_line
			(start -0.67945 0.3048)
			(end -0.67945 -0.305054)
			(stroke
				(width 0.1)
				(type default)
			)
			(layer "F.Fab")
		)
		(fp_line
			(start -0.12065 -0.305054)
			(end -0.12065 -0.2794)
			(stroke
				(width 0.1)
				(type default)
			)
			(layer "F.Fab")
		)
		(fp_line
			(start -0.12065 -0.2794)
			(end 0.12065 -0.2794)
			(stroke
				(width 0.1)
				(type default)
			)
			(layer "F.Fab")
		)
		(fp_line
			(start -0.12065 0.2794)
			(end -0.12065 0.3048)
			(stroke
				(width 0.1)
				(type default)
			)
			(layer "F.Fab")
		)
		(fp_line
			(start -0.12065 0.3048)
			(end -0.67945 0.3048)
			(stroke
				(width 0.1)
				(type default)
			)
			(layer "F.Fab")
		)
		(fp_line
			(start 0.120396 0.2794)
			(end -0.12065 0.2794)
			(stroke
				(width 0.1)
				(type default)
			)
			(layer "F.Fab")
		)
		(fp_line
			(start 0.120396 0.3048)
			(end 0.120396 0.2794)
			(stroke
				(width 0.1)
				(type default)
			)
			(layer "F.Fab")
		)
		(fp_line
			(start 0.12065 -0.3048)
			(end 0.67945 -0.3048)
			(stroke
				(width 0.1)
				(type default)
			)
			(layer "F.Fab")
		)
		(fp_line
			(start 0.12065 -0.2794)
			(end 0.12065 -0.3048)
			(stroke
				(width 0.1)
				(type default)
			)
			(layer "F.Fab")
		)
		(fp_line
			(start 0.67945 -0.3048)
			(end 0.67945 0.3048)
			(stroke
				(width 0.1)
				(type default)
			)
			(layer "F.Fab")
		)
		(fp_line
			(start 0.67945 0.3048)
			(end 0.120396 0.3048)
			(stroke
				(width 0.1)
				(type default)
			)
			(layer "F.Fab")
		)
		(pad "1" smd circle
			(at -0.40005 0)
			(size 0 0)
			(layers "F.Cu" "F.Mask" "F.Paste")
			(net "P3V3_AUX")
		)
		(pad "2" smd circle
			(at 0.40005 0)
			(size 0 0)
			(layers "F.Cu" "F.Mask" "F.Paste")
			(net "ADC128_A0")
		)
	)
)
